#ISCELL
  mstr_misc dns *
  *
#ISCELL
  pure_quanta quanta_title_block_c *
  *
#ISCELL
  pure_quanta_power cad_note *
  *
#ISCELL
  standard offpage *
  page82_i10
#ISCELL
  standard offpage *
  page82_i100
#ISCELL
  standard offpage *
  page82_i101
#CELL
  pure_quanta q_cap *
  page82_i102
#CELL
  pure_quanta q_cap *
  page82_i103
#CELL
  pure_quanta q_cap *
  page82_i104
#CELL
  pure_quanta q_cap *
  page82_i105
#CELL
  pure_quanta q_cap *
  page82_i106
#CELL
  pure_quanta q_cap *
  page82_i107
#CELL
  pure_quanta q_cap *
  page82_i108
#CELL
  pure_quanta q_cap *
  page82_i109
#ISCELL
  standard offpage *
  page82_i11
#CELL
  pure_quanta q_cap *
  page82_i110
#CELL
  pure_quanta q_cap *
  page82_i111
#CELL
  pure_quanta q_cap *
  page82_i112
#CELL
  pure_quanta q_cap *
  page82_i113
#CELL
  pure_quanta q_cap *
  page82_i114
#ISCELL
  pure_quanta_power gnd *
  page82_i115
#ISCELL
  pure_quanta_power vcc_core *
  page82_i116
#ISCELL
  pure_quanta_power gnd *
  page82_i117
#CELL
  pure_quanta q_res *
  page82_i118
#ISCELL
  mstr_symbols gnd *
  page82_i119
#ISCELL
  standard offpage *
  page82_i12
#CELL
  pure_quanta q_res *
  page82_i120
#ISCELL
  pure_quanta_power gnd *
  page82_i121
#ISCELL
  pure_quanta_power gnd *
  page82_i122
#ISCELL
  mstr_symbols gnd *
  page82_i123
#CELL
  pure_quanta q_res *
  page82_i124
#CELL
  pure_quanta q_res *
  page82_i125
#CELL
  pure_quanta q_res *
  page82_i126
#ISCELL
  mstr_symbols gnd *
  page82_i127
#CELL
  pure_quanta q_res *
  page82_i128
#ISCELL
  standard offpage *
  page82_i129
#ISCELL
  standard offpage *
  page82_i13
#ISCELL
  standard offpage *
  page82_i130
#ISCELL
  standard offpage *
  page82_i131
#ISCELL
  standard offpage *
  page82_i132
#ISCELL
  standard offpage *
  page82_i133
#ISCELL
  standard offpage *
  page82_i134
#CELL
  pure_quanta q_cap *
  page82_i135
#CELL
  pure_quanta q_res *
  page82_i137
#ISCELL
  standard offpage *
  page82_i139
#ISCELL
  standard offpage *
  page82_i14
#ISCELL
  pure_quanta_power universal_gnd *
  page82_i140
#CELL
  pure_quanta q_res *
  page82_i141
#ISCELL
  standard offpage *
  page82_i142
#CELL
  pure_quanta q_res *
  page82_i143
#ISCELL
  pure_quanta_power gnd *
  page82_i144
#ISCELL
  standard offpage *
  page82_i145
#CELL
  pure_quanta q_res *
  page82_i146
#ISCELL
  standard offpage *
  page82_i147
#ISCELL
  standard offpage *
  page82_i148
#ISCELL
  standard offpage *
  page82_i15
#ISCELL
  pure_quanta_power gnd *
  page82_i150
#CELL
  pure_quanta q_res *
  page82_i151
#CELL
  pure_quanta q_res *
  page82_i152
#ISCELL
  standard offpage *
  page82_i153
#CELL
  pure_quanta q_res *
  page82_i154
#ISCELL
  standard offpage *
  page82_i155
#CELL
  pure_quanta q_res *
  page82_i156
#CELL
  pure_quanta q_res *
  page82_i157
#ISCELL
  standard offpage *
  page82_i158
#ISCELL
  standard offpage *
  page82_i159
#ISCELL
  standard offpage *
  page82_i16
#ISCELL
  standard offpage *
  page82_i160
#ISCELL
  standard offpage *
  page82_i161
#CELL
  pure_quanta q_res *
  page82_i162
#CELL
  pure_quanta q_res *
  page82_i163
#ISCELL
  pure_quanta_power gnd *
  page82_i164
#ISCELL
  pure_quanta_power gnd *
  page82_i165
#CELL
  pure_quanta q_res *
  page82_i166
#ISCELL
  standard offpage *
  page82_i167
#ISCELL
  pure_quanta_power gnd *
  page82_i169
#ISCELL
  standard offpage *
  page82_i17
#CELL
  pure_quanta q_res *
  page82_i170
#CELL
  pure_quanta q_res *
  page82_i171
#ISCELL
  standard offpage *
  page82_i18
#ISCELL
  standard offpage *
  page82_i19
#ISCELL
  standard offpage *
  page82_i20
#ISCELL
  standard offpage *
  page82_i21
#ISCELL
  standard offpage *
  page82_i22
#CELL
  pure_quanta q_res *
  page82_i33
#CELL
  pure_quanta q_res *
  page82_i35
#CELL
  pure_quanta q_res *
  page82_i36
#ISCELL
  pure_quanta_power universal_power *
  page82_i37
#CELL
  pure_quanta q_res *
  page82_i38
#CELL
  pure_quanta q_res *
  page82_i39
#ISCELL
  standard offpage *
  page82_i4
#CELL
  pure_quanta q_res *
  page82_i40
#CELL
  pure_quanta q_res *
  page82_i41
#ISCELL
  standard offpage *
  page82_i5
#CELL
  pure_quanta q_res *
  page82_i53
#CELL
  pure_quanta q_res *
  page82_i54
#CELL
  pure_quanta q_res *
  page82_i56
#CELL
  pure_quanta q_res *
  page82_i57
#CELL
  pure_quanta q_res *
  page82_i58
#CELL
  pure_quanta q_res *
  page82_i59
#ISCELL
  standard offpage *
  page82_i6
#CELL
  pure_quanta q_res *
  page82_i60
#CELL
  pure_quanta q_res *
  page82_i61
#CELL
  pure_quanta q_res *
  page82_i62
#ISCELL
  pure_quanta_power vcc_core *
  page82_i63
#CELL
  pure_quanta q_res *
  page82_i64
#ISCELL
  standard offpage *
  page82_i65
#ISCELL
  standard offpage *
  page82_i66
#ISCELL
  standard offpage *
  page82_i67
#ISCELL
  standard offpage *
  page82_i68
#ISCELL
  standard offpage *
  page82_i69
#ISCELL
  standard offpage *
  page82_i7
#ISCELL
  pure_quanta_power vcc_core *
  page82_i70
#CELL
  pure_quanta q_res *
  page82_i72
#CELL
  pure_quanta q_res *
  page82_i73
#CELL
  pure_quanta q_res *
  page82_i74
#ISCELL
  pure_quanta_power vcc_core *
  page82_i75
#CELL
  pure_quanta q_res *
  page82_i76
#CELL
  pure_quanta q_res *
  page82_i77
#ISCELL
  pure_quanta_power vcc_core *
  page82_i78
#CELL
  pure_quanta q_cap *
  page82_i79
#ISCELL
  standard offpage *
  page82_i8
#CELL
  pure_quanta q_cap *
  page82_i80
#CELL
  pure_quanta q_cap *
  page82_i81
#CELL
  pure_quanta q_cap *
  page82_i82
#CELL
  pure_quanta q_cap *
  page82_i83
#CELL
  pure_quanta q_cap *
  page82_i84
#CELL
  pure_quanta q_cap *
  page82_i85
#CELL
  pure_quanta q_cap *
  page82_i86
#CELL
  pure_quanta q_cap *
  page82_i87
#ISCELL
  pure_quanta_power gnd *
  page82_i88
#ISCELL
  pure_quanta_power vcc_core *
  page82_i89
#ISCELL
  standard offpage *
  page82_i9
#ISCELL
  pure_quanta_power gnd *
  page82_i90
#ISCELL
  pure_quanta_power gnd *
  page82_i91
#ISCELL
  pure_quanta_power gnd *
  page82_i92
#CELL
  pure_quanta q_res *
  page82_i93
#CELL
  pure_quanta q_res *
  page82_i94
#CELL
  pure_quanta q_res *
  page82_i95
#ISCELL
  pure_quanta_power gnd *
  page82_i96
#CELL
  pure_quanta q_res *
  page82_i97
#ISCELL
  standard offpage *
  page82_i98
#ISCELL
  standard offpage *
  page82_i99
